Testpoint Report Status for Project:16369-1

Total # of Nets  : 103

Number of nets with "No_Test" property      :   0
Number of nets with testpoints assigned >1  :   1
Number of nets with testpoints assigned =1  :   97
Number of nets with testpoints assigned =0  :   5

Percent (All nets)                              :  95.15%
Percent (All nets Excluded "No_Test" property)  :  95.15%

GND                               4

DEBUG_CARD_A_PRSNT                1
DEBUG_CARD_B_PRSNT                1
DEBUG_HDR_A_UART_SEL              1
DEBUG_HDR_B_UART_SEL              1
DEBUG_RST_A_BTN_N                 1
DEBUG_RST_B_BTN_N                 1
DEBUG_USB_A_DN                    1
DEBUG_USB_A_DP                    1
DEBUG_USB_B_DN                    1
DEBUG_USB_B_DP                    1
D_FLIP_A_D                        1
D_FLIP_A_Q#                       1
D_FLIP_B_D                        1
D_FLIP_B_Q#                       1
D_FLIP_CLR_A#                     1
D_FLIP_CLR_B#                     1
D_FLIP_PRE_A#                     1
D_FLIP_PRE_B#                     1
FAULT_LED_A                       1
FAULT_LED_B                       1
I2C_DEBUG_A_SCL                   1
I2C_DEBUG_A_SCL_L                 1
I2C_DEBUG_A_SCL_R                 1
I2C_DEBUG_A_SDA                   1
I2C_DEBUG_A_SDA_L                 1
I2C_DEBUG_A_SDA_R                 1
I2C_DEBUG_B_SCL                   1
I2C_DEBUG_B_SCL_L                 1
I2C_DEBUG_B_SCL_R                 1
I2C_DEBUG_B_SDA                   1
I2C_DEBUG_B_SDA_L                 1
I2C_DEBUG_B_SDA_R                 1
I2C_DPB_A_SCL                     1
I2C_DPB_A_SDA                     1
I2C_DPB_B_SCL                     1
I2C_DPB_B_SDA                     1
IO_EXP_A_RESET#_FLT               1
P3V3_STBY_A                       1
P3V3_STBY_B                       1
P5V_USB_A                         1
P5V_VBUS_A                        1
P5V_VBUS_B                        1
PWR_BTN_A                         1
PWR_BTN_B                         1
PWR_BTN_LED_A_R                   1
PWR_BTN_LED_B_R                   1
PWR_LED_A_N                       1
PWR_LED_B_N                       1
RST_A_TS                          1
RST_B_TS                          1
SYS_FAULT_A_R                     1
SYS_FAULT_B_R                     1
SYS_RESET_BTN_A                   1
SYS_RESET_BTN_A_N                 1
SYS_RESET_BTN_A_N_R               1
SYS_RESET_BTN_B                   1
SYS_RESET_BTN_B_N                 1
SYS_RESET_BTN_B_N_R               1
TCA9555_A_A0                      1
TCA9555_A_A1                      1
TCA9555_A_A2                      1
TCA9555_B_A0                      1
TCA9555_B_A1                      1
TCA9555_B_A2                      1
TEMP_1_A1                         1
TEMP_1_A2                         1
TEMP_1_ALERT                      1
TEMP_1_SCL                        1
TEMP_1_SDA                        1
TEMP_2_A0                         1
TEMP_2_A1                         1
TEMP_2_A2                         1
TEMP_2_ALERT                      1
TEMP_2_SCL                        1
TEMP_2_SDA                        1
UART_A_RX                         1
UART_A_TX                         1
UART_B_RX                         1
UART_B_TX                         1
UART_DEBUG_A_RX                   1
UART_DEBUG_A_TX                   1
UART_DEBUG_B_RX                   1
UART_DEBUG_B_TX                   1
UART_EXP_A_RX                     1
UART_EXP_A_TX                     1
UART_EXP_B_RX                     1
UART_EXP_B_TX                     1
UART_IOC_A_RX                     1
UART_IOC_A_TX                     1
UART_IOC_B_RX                     1
UART_IOC_B_TX                     1
UART_SEL_A_MUX                    1
UART_SEL_A_MUX_R                  1
UART_SEL_B_MUX                    1
UART_SEL_B_MUX_R                  1
USB_CONN_A_GND                    1
USB_CONN_B_GND                    1

IO_EXP_B_RESET#_FLT               0
P5V_USB_B                         0
PWR_BTN_A_CONN                    0
PWR_BTN_B_CONN                    0
TEMP_1_A0                         0
